# SCM (Grand Teton) — schematic netlist excerpt (pin names and nets, part order shuffled) for the footprints in the layout excerpt that follows; sources: Cadence DE-HDL packaged netlist, KiCad conversion of 12092022_DA0F0TMDCD0_F0T_Management_Board_D_brd_V3_OCP.brd

R357  Q_RES  120 1% CHIP  pkg 0402LF  page 20 : A = M_BMC_DDR4_MA<6> ; B = P1V2_AUX

(kicad_pcb
	(version 20260206)
	(generator "pcbnew")
	(generator_version "10.0")
	(general
		(thickness 1.6)
		(legacy_teardrops no)
	)
	(paper "A4")
	(title_block
		(title "12092022_DA0F0TMDCD0_F0T_Management_Board_D_brd_V3_OCP.brd")
		(comment 1 "Grand Teton / footprints 1057-1057 of 1440")
	)
	(layers
		(0 "F.Cu" signal "TOP")
		(4 "In1.Cu" signal "GND")
		(6 "In2.Cu" signal "IN1")
		(8 "In3.Cu" signal "GND1")
		(10 "In4.Cu" signal "IN2")
		(12 "In5.Cu" signal "VCC")
		(14 "In6.Cu" signal "VCC1")
		(16 "In7.Cu" signal "IN3")
		(18 "In8.Cu" signal "GND2")
		(20 "In9.Cu" signal "IN4")
		(22 "In10.Cu" signal "GND3")
		(2 "B.Cu" signal "BOTTOM")
		(9 "F.Adhes" user "F.Adhesive")
		(11 "B.Adhes" user "B.Adhesive")
		(13 "F.Paste" user "Package Geometry/Pastemask Top")
		(15 "B.Paste" user "Package Geometry/Pastemask Bottom")
		(5 "F.SilkS" user "Ref Des/Silkscreen Top")
		(7 "B.SilkS" user "Ref Des/Silkscreen Bottom")
		(1 "F.Mask" user "Board Geometry/Soldermask Top")
		(3 "B.Mask" user "Board Geometry/Soldermask Bottom")
		(17 "Dwgs.User" user "User.Drawings")
		(19 "Cmts.User" user "User.Comments")
		(21 "Eco1.User" user "User.Eco1")
		(23 "Eco2.User" user "User.Eco2")
		(25 "Edge.Cuts" user "Board Geometry/Outline")
		(27 "Margin" user)
		(31 "F.CrtYd" user "Package Geometry/Place Bound Top")
		(29 "B.CrtYd" user "Package Geometry/Place Bound Bottom")
		(35 "F.Fab" user "Ref Des/Assembly Top")
		(33 "B.Fab" user "Ref Des/Assembly Bottom")
	)
	(footprint ""
		(layer "B.Cu")
		(at 77.707744 -37.559488 90)
		(property "Reference" "R357"
			(at 0 0 90)
			(layer "B.SilkS")
			(hide yes)
			(effects
				(font
					(size 1.27 1.27)
				)
				(justify mirror)
			)
		)
		(property "Value" ""
			(at 0 0 90)
			(layer "B.Fab")
			(effects
				(font
					(size 1.27 1.27)
				)
				(justify mirror)
			)
		)
		(duplicate_pad_numbers_are_jumpers no)
		(fp_line
			(start 0.7874 -0.4064)
			(end -0.7874 -0.4064)
			(stroke
				(width 0.1524)
				(type default)
			)
			(layer "B.SilkS")
		)
		(fp_line
			(start -0.7874 -0.4064)
			(end -0.7874 0.4064)
			(stroke
				(width 0.1524)
				(type default)
			)
			(layer "B.SilkS")
		)
		(fp_line
			(start 0.7874 0.4064)
			(end 0.7874 -0.4064)
			(stroke
				(width 0.1524)
				(type default)
			)
			(layer "B.SilkS")
		)
		(fp_line
			(start -0.7874 0.4064)
			(end 0.7874 0.4064)
			(stroke
				(width 0.1524)
				(type default)
			)
			(layer "B.SilkS")
		)
		(fp_line
			(start 0.67945 -0.305054)
			(end 0.12065 -0.305054)
			(stroke
				(width 0.1)
				(type default)
			)
			(layer "B.Fab")
		)
		(fp_line
			(start 0.12065 -0.305054)
			(end 0.12065 -0.2794)
			(stroke
				(width 0.1)
				(type default)
			)
			(layer "B.Fab")
		)
		(fp_line
			(start -0.12065 -0.3048)
			(end -0.67945 -0.3048)
			(stroke
				(width 0.1)
				(type default)
			)
			(layer "B.Fab")
		)
		(fp_line
			(start -0.67945 -0.3048)
			(end -0.67945 0.3048)
			(stroke
				(width 0.1)
				(type default)
			)
			(layer "B.Fab")
		)
		(fp_line
			(start 0.12065 -0.2794)
			(end -0.12065 -0.2794)
			(stroke
				(width 0.1)
				(type default)
			)
			(layer "B.Fab")
		)
		(fp_line
			(start -0.12065 -0.2794)
			(end -0.12065 -0.3048)
			(stroke
				(width 0.1)
				(type default)
			)
			(layer "B.Fab")
		)
		(fp_line
			(start 0.12065 0.2794)
			(end 0.12065 0.3048)
			(stroke
				(width 0.1)
				(type default)
			)
			(layer "B.Fab")
		)
		(fp_line
			(start -0.120396 0.2794)
			(end 0.12065 0.2794)
			(stroke
				(width 0.1)
				(type default)
			)
			(layer "B.Fab")
		)
		(fp_line
			(start 0.67945 0.3048)
			(end 0.67945 -0.305054)
			(stroke
				(width 0.1)
				(type default)
			)
			(layer "B.Fab")
		)
		(fp_line
			(start 0.12065 0.3048)
			(end 0.67945 0.3048)
			(stroke
				(width 0.1)
				(type default)
			)
			(layer "B.Fab")
		)
		(fp_line
			(start -0.120396 0.3048)
			(end -0.120396 0.2794)
			(stroke
				(width 0.1)
				(type default)
			)
			(layer "B.Fab")
		)
		(fp_line
			(start -0.67945 0.3048)
			(end -0.120396 0.3048)
			(stroke
				(width 0.1)
				(type default)
			)
			(layer "B.Fab")
		)
		(pad "1" smd circle
			(at 0.40005 0 270)
			(size 0 0)
			(layers "B.Cu" "B.Mask" "B.Paste")
			(net "M_BMC_DDR4_MA<6>")
		)
		(pad "2" smd circle
			(at -0.40005 0 270)
			(size 0 0)
			(layers "B.Cu" "B.Mask" "B.Paste")
			(net "P1V2_AUX")
		)
	)
)
